#ISCELL
  cls sheet_a1_enterprise *
  *
#CELL
  passive capacitor *
  page523_i10
#CELL
  passive resistor *
  page523_i104
#ISCELL
  cls offpage_out *
  page523_i105
#ISCELL
  cls gnd_sg *
  page523_i106
#ISCELL
  cls offpage_in *
  page523_i108
#CELL
  passive resistor *
  page523_i109
#CELL
  stdlogic tps54824rnvr_vqfn18 *
  page523_i11
#CELL
  passive capacitor *
  page523_i12
#CELL
  passive capacitor *
  page523_i13
#CELL
  passive capacitor *
  page523_i14
#CELL
  passive resistor *
  page523_i15
#CELL
  passive resistor *
  page523_i16
#CELL
  passive capacitor *
  page523_i17
#ISCELL
  cls gnd_sg *
  page523_i18
#CELL
  passive capacitor *
  page523_i19
#ISCELL
  cls gnd_sg *
  page523_i20
#CELL
  passive resistor *
  page523_i23
#CELL
  passive capacitor *
  page523_i24
#CELL
  passive inductor_2 *
  page523_i25
#CELL
  passive resistor *
  page523_i26
#CELL
  passive capacitor *
  page523_i28
#CELL
  passive resistor *
  page523_i29
#CELL
  passive resistor *
  page523_i30
#CELL
  passive capacitor *
  page523_i31
#ISCELL
  cls gnd_sg *
  page523_i32
#CELL
  passive capacitor *
  page523_i33
#CELL
  passive capacitor *
  page523_i34
#CELL
  passive capacitor *
  page523_i35
#ISCELL
  cls gnd_sg *
  page523_i36
#CELL
  passive capacitor *
  page523_i37
#CELL
  mech solder_preform *
  page523_i39
#ISCELL
  cls vcc *
  page523_i43
#CELL
  passive resistor *
  page523_i44
#ISCELL
  cls gnd_sg *
  page523_i45
#CELL
  passive capacitor *
  page523_i46
#ISCELL
  cls vcc *
  page523_i47
#CELL
  passive ferritebead *
  page523_i48
#CELL
  passive capacitor *
  page523_i50
#CELL
  passive resistor *
  page523_i51
#CELL
  passive resistor *
  page523_i54
#CELL
  passive resistor *
  page523_i56
#CELL
  passive resistor *
  page523_i57
#ISCELL
  cls gnd_sg *
  page523_i6
#CELL
  passive capacitor *
  page523_i7
#CELL
  passive capacitor *
  page523_i9
#ISCELL
  cls vcc *
  page523_i97
